(kicad_pcb
	(version 20260206)
	(generator "pcbnew")
	(generator_version "10.0")
	(general
		(thickness 1.6)
		(legacy_teardrops no)
	)
	(paper "A4")
	(title_block
		(title "04192023_DAF0TMB3IC0_F0TG_MB_C_brd_V02_OCP.brd")
		(comment 1 "Grand Teton / footprints 7784-7790 of 8354")
	)
	(layers
		(0 "F.Cu" signal "TOP")
		(4 "In1.Cu" signal "GND")
		(6 "In2.Cu" signal "IN1")
		(8 "In3.Cu" signal "GND1")
		(10 "In4.Cu" signal "IN2")
		(12 "In5.Cu" signal "GND2")
		(14 "In6.Cu" signal "IN3")
		(16 "In7.Cu" signal "GND3")
		(18 "In8.Cu" signal "VCC")
		(20 "In9.Cu" signal "VCC1")
		(22 "In10.Cu" signal "GND4")
		(24 "In11.Cu" signal "IN4")
		(26 "In12.Cu" signal "GND5")
		(28 "In13.Cu" signal "IN5")
		(30 "In14.Cu" signal "GND6")
		(32 "In15.Cu" signal "IN6")
		(34 "In16.Cu" signal "GND7")
		(2 "B.Cu" signal "BOTTOM")
		(9 "F.Adhes" user "F.Adhesive")
		(11 "B.Adhes" user "B.Adhesive")
		(13 "F.Paste" user "Package Geometry/Pastemask Top")
		(15 "B.Paste" user "Package Geometry/Pastemask Bottom")
		(5 "F.SilkS" user "Ref Des/Silkscreen Top")
		(7 "B.SilkS" user "Ref Des/Silkscreen Bottom")
		(1 "F.Mask" user "Board Geometry/Soldermask Top")
		(3 "B.Mask" user "Board Geometry/Soldermask Bottom")
		(17 "Dwgs.User" user "User.Drawings")
		(19 "Cmts.User" user "User.Comments")
		(21 "Eco1.User" user "User.Eco1")
		(23 "Eco2.User" user "User.Eco2")
		(25 "Edge.Cuts" user "Board Geometry/Outline")
		(27 "Margin" user)
		(31 "F.CrtYd" user "Package Geometry/Place Bound Top")
		(29 "B.CrtYd" user "Package Geometry/Place Bound Bottom")
		(35 "F.Fab" user "Ref Des/Assembly Top")
		(33 "B.Fab" user "Ref Des/Assembly Bottom")
	)
	(footprint ""
		(layer "B.Cu")
		(at 151.819102 -390.560052 90)
		(property "Reference" "C399"
			(at 0 0 90)
			(layer "B.SilkS")
			(hide yes)
			(effects
				(font
					(size 1.27 1.27)
				)
				(justify mirror)
			)
		)
		(property "Value" ""
			(at 0 0 90)
			(layer "B.Fab")
			(effects
				(font
					(size 1.27 1.27)
				)
				(justify mirror)
			)
		)
		(duplicate_pad_numbers_are_jumpers no)
		(fp_line
			(start 0.7874 -0.4064)
			(end -0.7874 -0.4064)
			(stroke
				(width 0.1524)
				(type default)
			)
			(layer "B.SilkS")
		)
		(fp_line
			(start -0.7874 -0.4064)
			(end -0.7874 0.4064)
			(stroke
				(width 0.1524)
				(type default)
			)
			(layer "B.SilkS")
		)
		(fp_line
			(start 0.7874 0.4064)
			(end 0.7874 -0.4064)
			(stroke
				(width 0.1524)
				(type default)
			)
			(layer "B.SilkS")
		)
		(fp_line
			(start -0.7874 0.4064)
			(end 0.7874 0.4064)
			(stroke
				(width 0.1524)
				(type default)
			)
			(layer "B.SilkS")
		)
		(fp_line
			(start 0.67945 -0.305054)
			(end 0.12065 -0.305054)
			(stroke
				(width 0.1)
				(type default)
			)
			(layer "B.Fab")
		)
		(fp_line
			(start 0.12065 -0.305054)
			(end 0.12065 -0.2794)
			(stroke
				(width 0.1)
				(type default)
			)
			(layer "B.Fab")
		)
		(fp_line
			(start -0.12065 -0.3048)
			(end -0.67945 -0.3048)
			(stroke
				(width 0.1)
				(type default)
			)
			(layer "B.Fab")
		)
		(fp_line
			(start -0.67945 -0.3048)
			(end -0.67945 0.3048)
			(stroke
				(width 0.1)
				(type default)
			)
			(layer "B.Fab")
		)
		(fp_line
			(start 0.12065 -0.2794)
			(end -0.12065 -0.2794)
			(stroke
				(width 0.1)
				(type default)
			)
			(layer "B.Fab")
		)
		(fp_line
			(start -0.12065 -0.2794)
			(end -0.12065 -0.3048)
			(stroke
				(width 0.1)
				(type default)
			)
			(layer "B.Fab")
		)
		(fp_line
			(start 0.12065 0.2794)
			(end 0.12065 0.3048)
			(stroke
				(width 0.1)
				(type default)
			)
			(layer "B.Fab")
		)
		(fp_line
			(start -0.120396 0.2794)
			(end 0.12065 0.2794)
			(stroke
				(width 0.1)
				(type default)
			)
			(layer "B.Fab")
		)
		(fp_line
			(start 0.67945 0.3048)
			(end 0.67945 -0.305054)
			(stroke
				(width 0.1)
				(type default)
			)
			(layer "B.Fab")
		)
		(fp_line
			(start 0.12065 0.3048)
			(end 0.67945 0.3048)
			(stroke
				(width 0.1)
				(type default)
			)
			(layer "B.Fab")
		)
		(fp_line
			(start -0.120396 0.3048)
			(end -0.120396 0.2794)
			(stroke
				(width 0.1)
				(type default)
			)
			(layer "B.Fab")
		)
		(fp_line
			(start -0.67945 0.3048)
			(end -0.120396 0.3048)
			(stroke
				(width 0.1)
				(type default)
			)
			(layer "B.Fab")
		)
		(pad "1" smd circle
			(at 0.40005 0 270)
			(size 0 0)
			(layers "B.Cu" "B.Mask" "B.Paste")
			(net "P0V9_CPU1_RT2_2A")
		)
		(pad "2" smd circle
			(at -0.40005 0 270)
			(size 0 0)
			(layers "B.Cu" "B.Mask" "B.Paste")
			(net "GND")
		)
	)
	(footprint ""
		(layer "B.Cu")
		(at 295.416986 -424.118786 180)
		(property "Reference" "R1219"
			(at 0 0 0)
			(layer "B.SilkS")
			(hide yes)
			(effects
				(font
					(size 1.27 1.27)
				)
				(justify mirror)
			)
		)
		(property "Value" ""
			(at 0 0 0)
			(layer "B.Fab")
			(effects
				(font
					(size 1.27 1.27)
				)
				(justify mirror)
			)
		)
		(duplicate_pad_numbers_are_jumpers no)
		(fp_line
			(start 0.32512 0.175006)
			(end 0.32512 -0.175006)
			(stroke
				(width 0.1)
				(type default)
			)
			(layer "B.Fab")
		)
		(fp_line
			(start 0.32512 -0.175006)
			(end -0.32512 -0.175006)
			(stroke
				(width 0.1)
				(type default)
			)
			(layer "B.Fab")
		)
		(fp_line
			(start -0.32512 0.175006)
			(end 0.32512 0.175006)
			(stroke
				(width 0.1)
				(type default)
			)
			(layer "B.Fab")
		)
		(fp_line
			(start -0.32512 -0.175006)
			(end -0.32512 0.175006)
			(stroke
				(width 0.1)
				(type default)
			)
			(layer "B.Fab")
		)
		(pad "1" smd rect
			(at 0.2667 0)
			(size 0.3048 0.381)
			(layers "B.Cu" "B.Mask" "B.Paste")
			(net "GND")
		)
		(pad "2" smd rect
			(at -0.2667 0 180)
			(size 0.3048 0.381)
			(layers "B.Cu" "B.Mask" "B.Paste")
			(net "RT_ROM_MUX5_OE_N")
		)
	)
	(footprint ""
		(layer "B.Cu")
		(at 183.3245 -404.051262 180)
		(property "Reference" "R3924"
			(at 0 0 0)
			(layer "B.SilkS")
			(hide yes)
			(effects
				(font
					(size 1.27 1.27)
				)
				(justify mirror)
			)
		)
		(property "Value" ""
			(at 0 0 0)
			(layer "B.Fab")
			(effects
				(font
					(size 1.27 1.27)
				)
				(justify mirror)
			)
		)
		(duplicate_pad_numbers_are_jumpers no)
		(fp_line
			(start 0.7874 0.4064)
			(end 0.7874 -0.4064)
			(stroke
				(width 0.1524)
				(type default)
			)
			(layer "B.SilkS")
		)
		(fp_line
			(start 0.7874 -0.4064)
			(end -0.7874 -0.4064)
			(stroke
				(width 0.1524)
				(type default)
			)
			(layer "B.SilkS")
		)
		(fp_line
			(start -0.7874 0.4064)
			(end 0.7874 0.4064)
			(stroke
				(width 0.1524)
				(type default)
			)
			(layer "B.SilkS")
		)
		(fp_line
			(start -0.7874 -0.4064)
			(end -0.7874 0.4064)
			(stroke
				(width 0.1524)
				(type default)
			)
			(layer "B.SilkS")
		)
		(fp_line
			(start 0.67945 0.3048)
			(end 0.67945 -0.305054)
			(stroke
				(width 0.1)
				(type default)
			)
			(layer "B.Fab")
		)
		(fp_line
			(start 0.67945 -0.305054)
			(end 0.12065 -0.305054)
			(stroke
				(width 0.1)
				(type default)
			)
			(layer "B.Fab")
		)
		(fp_line
			(start 0.12065 0.3048)
			(end 0.67945 0.3048)
			(stroke
				(width 0.1)
				(type default)
			)
			(layer "B.Fab")
		)
		(fp_line
			(start 0.12065 0.2794)
			(end 0.12065 0.3048)
			(stroke
				(width 0.1)
				(type default)
			)
			(layer "B.Fab")
		)
		(fp_line
			(start 0.12065 -0.2794)
			(end -0.12065 -0.2794)
			(stroke
				(width 0.1)
				(type default)
			)
			(layer "B.Fab")
		)
		(fp_line
			(start 0.12065 -0.305054)
			(end 0.12065 -0.2794)
			(stroke
				(width 0.1)
				(type default)
			)
			(layer "B.Fab")
		)
		(fp_line
			(start -0.120396 0.3048)
			(end -0.120396 0.2794)
			(stroke
				(width 0.1)
				(type default)
			)
			(layer "B.Fab")
		)
		(fp_line
			(start -0.120396 0.2794)
			(end 0.12065 0.2794)
			(stroke
				(width 0.1)
				(type default)
			)
			(layer "B.Fab")
		)
		(fp_line
			(start -0.12065 -0.2794)
			(end -0.12065 -0.3048)
			(stroke
				(width 0.1)
				(type default)
			)
			(layer "B.Fab")
		)
		(fp_line
			(start -0.12065 -0.3048)
			(end -0.67945 -0.3048)
			(stroke
				(width 0.1)
				(type default)
			)
			(layer "B.Fab")
		)
		(fp_line
			(start -0.67945 0.3048)
			(end -0.120396 0.3048)
			(stroke
				(width 0.1)
				(type default)
			)
			(layer "B.Fab")
		)
		(fp_line
			(start -0.67945 -0.3048)
			(end -0.67945 0.3048)
			(stroke
				(width 0.1)
				(type default)
			)
			(layer "B.Fab")
		)
		(pad "1" smd circle
			(at 0.40005 0)
			(size 0 0)
			(layers "B.Cu" "B.Mask" "B.Paste")
			(net "IRQ_SML1_PMBUS_ALERT_N")
		)
		(pad "2" smd circle
			(at -0.40005 0)
			(size 0 0)
			(layers "B.Cu" "B.Mask" "B.Paste")
			(net "IRQ_SML1_PMBUS_ALERT")
		)
	)
	(footprint ""
		(layer "B.Cu")
		(at 90.209878 -140.82141 180)
		(property "Reference" "R8177"
			(at 0 0 0)
			(layer "B.SilkS")
			(hide yes)
			(effects
				(font
					(size 1.27 1.27)
				)
				(justify mirror)
			)
		)
		(property "Value" ""
			(at 0 0 0)
			(layer "B.Fab")
			(effects
				(font
					(size 1.27 1.27)
				)
				(justify mirror)
			)
		)
		(duplicate_pad_numbers_are_jumpers no)
		(fp_line
			(start 0.7874 0.4064)
			(end 0.7874 -0.4064)
			(stroke
				(width 0.1524)
				(type default)
			)
			(layer "B.SilkS")
		)
		(fp_line
			(start 0.7874 -0.4064)
			(end -0.7874 -0.4064)
			(stroke
				(width 0.1524)
				(type default)
			)
			(layer "B.SilkS")
		)
		(fp_line
			(start -0.7874 0.4064)
			(end 0.7874 0.4064)
			(stroke
				(width 0.1524)
				(type default)
			)
			(layer "B.SilkS")
		)
		(fp_line
			(start -0.7874 -0.4064)
			(end -0.7874 0.4064)
			(stroke
				(width 0.1524)
				(type default)
			)
			(layer "B.SilkS")
		)
		(fp_line
			(start 0.67945 0.3048)
			(end 0.67945 -0.305054)
			(stroke
				(width 0.1)
				(type default)
			)
			(layer "B.Fab")
		)
		(fp_line
			(start 0.67945 -0.305054)
			(end 0.12065 -0.305054)
			(stroke
				(width 0.1)
				(type default)
			)
			(layer "B.Fab")
		)
		(fp_line
			(start 0.12065 0.3048)
			(end 0.67945 0.3048)
			(stroke
				(width 0.1)
				(type default)
			)
			(layer "B.Fab")
		)
		(fp_line
			(start 0.12065 0.2794)
			(end 0.12065 0.3048)
			(stroke
				(width 0.1)
				(type default)
			)
			(layer "B.Fab")
		)
		(fp_line
			(start 0.12065 -0.2794)
			(end -0.12065 -0.2794)
			(stroke
				(width 0.1)
				(type default)
			)
			(layer "B.Fab")
		)
		(fp_line
			(start 0.12065 -0.305054)
			(end 0.12065 -0.2794)
			(stroke
				(width 0.1)
				(type default)
			)
			(layer "B.Fab")
		)
		(fp_line
			(start -0.120396 0.3048)
			(end -0.120396 0.2794)
			(stroke
				(width 0.1)
				(type default)
			)
			(layer "B.Fab")
		)
		(fp_line
			(start -0.120396 0.2794)
			(end 0.12065 0.2794)
			(stroke
				(width 0.1)
				(type default)
			)
			(layer "B.Fab")
		)
		(fp_line
			(start -0.12065 -0.2794)
			(end -0.12065 -0.3048)
			(stroke
				(width 0.1)
				(type default)
			)
			(layer "B.Fab")
		)
		(fp_line
			(start -0.12065 -0.3048)
			(end -0.67945 -0.3048)
			(stroke
				(width 0.1)
				(type default)
			)
			(layer "B.Fab")
		)
		(fp_line
			(start -0.67945 0.3048)
			(end -0.120396 0.3048)
			(stroke
				(width 0.1)
				(type default)
			)
			(layer "B.Fab")
		)
		(fp_line
			(start -0.67945 -0.3048)
			(end -0.67945 0.3048)
			(stroke
				(width 0.1)
				(type default)
			)
			(layer "B.Fab")
		)
		(pad "1" smd circle
			(at 0.40005 0)
			(size 0 0)
			(layers "B.Cu" "B.Mask" "B.Paste")
			(net "PVDDCR_CPU0_P1_PMALERT")
		)
		(pad "2" smd circle
			(at -0.40005 0)
			(size 0 0)
			(layers "B.Cu" "B.Mask" "B.Paste")
			(net "PVDDCR_CPU0_P1_PMALERT_R")
		)
	)
	(footprint ""
		(layer "B.Cu")
		(at 55.328058 -192.66027 180)
		(property "Reference" "C173"
			(at 0 0 0)
			(layer "B.SilkS")
			(hide yes)
			(effects
				(font
					(size 1.27 1.27)
				)
				(justify mirror)
			)
		)
		(property "Value" ""
			(at 0 0 0)
			(layer "B.Fab")
			(effects
				(font
					(size 1.27 1.27)
				)
				(justify mirror)
			)
		)
		(duplicate_pad_numbers_are_jumpers no)
		(fp_line
			(start 1.524 0.762)
			(end 1.524 -0.762)
			(stroke
				(width 0.1524)
				(type default)
			)
			(layer "B.SilkS")
		)
		(fp_line
			(start 1.524 -0.762)
			(end -1.524 -0.762)
			(stroke
				(width 0.1524)
				(type default)
			)
			(layer "B.SilkS")
		)
		(fp_line
			(start -1.524 0.762)
			(end 1.524 0.762)
			(stroke
				(width 0.1524)
				(type default)
			)
			(layer "B.SilkS")
		)
		(fp_line
			(start -1.524 -0.762)
			(end -1.524 0.762)
			(stroke
				(width 0.1524)
				(type default)
			)
			(layer "B.SilkS")
		)
		(fp_line
			(start 1.1049 0.724916)
			(end -1.1049 0.724916)
			(stroke
				(width 0.1)
				(type default)
			)
			(layer "B.Fab")
		)
		(fp_line
			(start 1.1049 -0.724916)
			(end 1.1049 0.724916)
			(stroke
				(width 0.1)
				(type default)
			)
			(layer "B.Fab")
		)
		(fp_line
			(start -1.1049 0.724916)
			(end -1.1049 -0.724916)
			(stroke
				(width 0.1)
				(type default)
			)
			(layer "B.Fab")
		)
		(fp_line
			(start -1.1049 -0.724916)
			(end 1.1049 -0.724916)
			(stroke
				(width 0.1)
				(type default)
			)
			(layer "B.Fab")
		)
		(pad "1" smd rect
			(at 0.889 0 180)
			(size 1.016 1.27)
			(layers "B.Cu" "B.Mask" "B.Paste")
			(net "P12V_MEM_CPU1")
		)
		(pad "2" smd rect
			(at -0.889 0 180)
			(size 1.016 1.27)
			(layers "B.Cu" "B.Mask" "B.Paste")
			(net "GND")
		)
	)
	(footprint ""
		(layer "B.Cu")
		(at 396.546578 -328.655172 180)
		(property "Reference" "R463"
			(at 0 0 0)
			(layer "B.SilkS")
			(hide yes)
			(effects
				(font
					(size 1.27 1.27)
				)
				(justify mirror)
			)
		)
		(property "Value" ""
			(at 0 0 0)
			(layer "B.Fab")
			(effects
				(font
					(size 1.27 1.27)
				)
				(justify mirror)
			)
		)
		(duplicate_pad_numbers_are_jumpers no)
		(fp_line
			(start 0.7874 0.4064)
			(end 0.7874 -0.4064)
			(stroke
				(width 0.1524)
				(type default)
			)
			(layer "B.SilkS")
		)
		(fp_line
			(start 0.7874 -0.4064)
			(end -0.7874 -0.4064)
			(stroke
				(width 0.1524)
				(type default)
			)
			(layer "B.SilkS")
		)
		(fp_line
			(start -0.7874 0.4064)
			(end 0.7874 0.4064)
			(stroke
				(width 0.1524)
				(type default)
			)
			(layer "B.SilkS")
		)
		(fp_line
			(start -0.7874 -0.4064)
			(end -0.7874 0.4064)
			(stroke
				(width 0.1524)
				(type default)
			)
			(layer "B.SilkS")
		)
		(fp_line
			(start 0.67945 0.3048)
			(end 0.67945 -0.305054)
			(stroke
				(width 0.1)
				(type default)
			)
			(layer "B.Fab")
		)
		(fp_line
			(start 0.67945 -0.305054)
			(end 0.12065 -0.305054)
			(stroke
				(width 0.1)
				(type default)
			)
			(layer "B.Fab")
		)
		(fp_line
			(start 0.12065 0.3048)
			(end 0.67945 0.3048)
			(stroke
				(width 0.1)
				(type default)
			)
			(layer "B.Fab")
		)
		(fp_line
			(start 0.12065 0.2794)
			(end 0.12065 0.3048)
			(stroke
				(width 0.1)
				(type default)
			)
			(layer "B.Fab")
		)
		(fp_line
			(start 0.12065 -0.2794)
			(end -0.12065 -0.2794)
			(stroke
				(width 0.1)
				(type default)
			)
			(layer "B.Fab")
		)
		(fp_line
			(start 0.12065 -0.305054)
			(end 0.12065 -0.2794)
			(stroke
				(width 0.1)
				(type default)
			)
			(layer "B.Fab")
		)
		(fp_line
			(start -0.120396 0.3048)
			(end -0.120396 0.2794)
			(stroke
				(width 0.1)
				(type default)
			)
			(layer "B.Fab")
		)
		(fp_line
			(start -0.120396 0.2794)
			(end 0.12065 0.2794)
			(stroke
				(width 0.1)
				(type default)
			)
			(layer "B.Fab")
		)
		(fp_line
			(start -0.12065 -0.2794)
			(end -0.12065 -0.3048)
			(stroke
				(width 0.1)
				(type default)
			)
			(layer "B.Fab")
		)
		(fp_line
			(start -0.12065 -0.3048)
			(end -0.67945 -0.3048)
			(stroke
				(width 0.1)
				(type default)
			)
			(layer "B.Fab")
		)
		(fp_line
			(start -0.67945 0.3048)
			(end -0.120396 0.3048)
			(stroke
				(width 0.1)
				(type default)
			)
			(layer "B.Fab")
		)
		(fp_line
			(start -0.67945 -0.3048)
			(end -0.67945 0.3048)
			(stroke
				(width 0.1)
				(type default)
			)
			(layer "B.Fab")
		)
		(pad "1" smd circle
			(at 0.40005 0)
			(size 0 0)
			(layers "B.Cu" "B.Mask" "B.Paste")
			(net "RST_CPU0_KBRST_R_N")
		)
		(pad "2" smd circle
			(at -0.40005 0)
			(size 0 0)
			(layers "B.Cu" "B.Mask" "B.Paste")
			(net "RST_CPU0_KBRST_N")
		)
	)
	(footprint ""
		(layer "B.Cu")
		(at 98.70313 -335.09712 90)
		(property "Reference" "PC426_5"
			(at 0 0 90)
			(layer "B.SilkS")
			(hide yes)
			(effects
				(font
					(size 1.27 1.27)
				)
				(justify mirror)
			)
		)
		(property "Value" ""
			(at 0 0 90)
			(layer "B.Fab")
			(effects
				(font
					(size 1.27 1.27)
				)
				(justify mirror)
			)
		)
		(duplicate_pad_numbers_are_jumpers no)
		(fp_line
			(start 1.524 -0.762)
			(end -1.524 -0.762)
			(stroke
				(width 0.1524)
				(type default)
			)
			(layer "B.SilkS")
		)
		(fp_line
			(start -1.524 -0.762)
			(end -1.524 0.762)
			(stroke
				(width 0.1524)
				(type default)
			)
			(layer "B.SilkS")
		)
		(fp_line
			(start 1.524 0.762)
			(end 1.524 -0.762)
			(stroke
				(width 0.1524)
				(type default)
			)
			(layer "B.SilkS")
		)
		(fp_line
			(start -1.524 0.762)
			(end 1.524 0.762)
			(stroke
				(width 0.1524)
				(type default)
			)
			(layer "B.SilkS")
		)
		(fp_line
			(start 1.1049 -0.724916)
			(end 1.1049 0.724916)
			(stroke
				(width 0.1)
				(type default)
			)
			(layer "B.Fab")
		)
		(fp_line
			(start -1.1049 -0.724916)
			(end 1.1049 -0.724916)
			(stroke
				(width 0.1)
				(type default)
			)
			(layer "B.Fab")
		)
		(fp_line
			(start 1.1049 0.724916)
			(end -1.1049 0.724916)
			(stroke
				(width 0.1)
				(type default)
			)
			(layer "B.Fab")
		)
		(fp_line
			(start -1.1049 0.724916)
			(end -1.1049 -0.724916)
			(stroke
				(width 0.1)
				(type default)
			)
			(layer "B.Fab")
		)
		(pad "1" smd rect
			(at 0.889 0 90)
			(size 1.016 1.27)
			(layers "B.Cu" "B.Mask" "B.Paste")
			(net "SW_P12V_AUX_PVDDCR_CPU1_P1_FLT")
		)
		(pad "2" smd rect
			(at -0.889 0 90)
			(size 1.016 1.27)
			(layers "B.Cu" "B.Mask" "B.Paste")
			(net "GND")
		)
	)
)
